# BASEBOARD_FAB2 (Tioga Pass) — schematic netlist excerpt (pin names and nets, part order shuffled) for the footprints in the layout excerpt that follows; sources: Cadence DE-HDL packaged netlist, KiCad conversion of Wiwynn_Tioga_Pass_MB.brd

C25W61  CAP_A  0.1UF 16V 10% X7R  pkg 0402V  page 149 : A = P3V3_STBY ; B = GND
R9P11  RES  10.0K 1% CHIP  pkg 0402  page 200 : A = A_P12V_STBY_FP_TRIGGER ; B = AGND_HSC
R6N10  RES  221 1.0% CHIP  pkg 0402  page 21 : A = SVID_ALERT0_CPU0_N ; B = SVID_ALERT0_CPU0_R_N

(kicad_pcb
	(version 20260206)
	(generator "pcbnew")
	(generator_version "10.0")
	(general
		(thickness 1.6)
		(legacy_teardrops no)
	)
	(paper "A4")
	(title_block
		(title "Wiwynn_Tioga_Pass_MB.brd")
		(comment 1 "Tioga Pass / footprints 2752-2754 of 4770")
	)
	(layers
		(0 "F.Cu" signal "TOP")
		(4 "In1.Cu" signal "L2GND")
		(6 "In2.Cu" signal "L3")
		(8 "In3.Cu" signal "L4GND")
		(10 "In4.Cu" signal "L5")
		(12 "In5.Cu" signal "L6GND")
		(14 "In6.Cu" signal "L7VCC")
		(16 "In7.Cu" signal "L8VCC")
		(18 "In8.Cu" signal "L9GND")
		(20 "In9.Cu" signal "L10")
		(22 "In10.Cu" signal "L11GND")
		(24 "In11.Cu" signal "L12")
		(26 "In12.Cu" signal "L13GND")
		(2 "B.Cu" signal "BOTTOM")
		(9 "F.Adhes" user "F.Adhesive")
		(11 "B.Adhes" user "B.Adhesive")
		(13 "F.Paste" user "Package Geometry/Pastemask Top")
		(15 "B.Paste" user "Package Geometry/Pastemask Bottom")
		(5 "F.SilkS" user "Ref Des/Silkscreen Top")
		(7 "B.SilkS" user "Ref Des/Silkscreen Bottom")
		(1 "F.Mask" user "Board Geometry/Soldermask Top")
		(3 "B.Mask" user "Board Geometry/Soldermask Bottom")
		(17 "Dwgs.User" user "User.Drawings")
		(19 "Cmts.User" user "User.Comments")
		(21 "Eco1.User" user "User.Eco1")
		(23 "Eco2.User" user "User.Eco2")
		(25 "Edge.Cuts" user "Board Geometry/Outline")
		(27 "Margin" user)
		(31 "F.CrtYd" user "Package Geometry/Place Bound Top")
		(29 "B.CrtYd" user "Package Geometry/Place Bound Bottom")
		(35 "F.Fab" user "Ref Des/Assembly Top")
		(33 "B.Fab" user "Ref Des/Assembly Bottom")
	)
	(footprint ""
		(layer "B.Cu")
		(at 411.479492 -31.107888 -90)
		(property "Reference" "C25W61"
			(at 0.8382 -0.67818 270)
			(unlocked yes)
			(layer "B.SilkS")
			(effects
				(font
					(size 0.4064 0.254)
					(thickness 0.1524)
				)
				(justify left mirror)
			)
		)
		(property "Value" ""
			(at 0 0 90)
			(layer "B.Fab")
			(effects
				(font
					(size 1.27 1.27)
				)
				(justify mirror)
			)
		)
		(duplicate_pad_numbers_are_jumpers no)
		(fp_poly
			(pts
				(xy -0.3048 -0.1016) (xy -0.3048 0.9906) (xy 0.3048 0.9906) (xy 0.3048 -0.1016)
			)
			(stroke
				(width 0)
				(type default)
			)
			(fill no)
			(layer "B.CrtYd")
		)
		(fp_line
			(start -0.3048 0.9906)
			(end -0.3048 -0.1016)
			(stroke
				(width 0.1)
				(type default)
			)
			(layer "B.Fab")
		)
		(fp_line
			(start 0.3048 0.9906)
			(end -0.3048 0.9906)
			(stroke
				(width 0.1)
				(type default)
			)
			(layer "B.Fab")
		)
		(fp_line
			(start -0.3048 -0.1016)
			(end 0.3048 -0.1016)
			(stroke
				(width 0.1)
				(type default)
			)
			(layer "B.Fab")
		)
		(fp_line
			(start 0.3048 -0.1016)
			(end 0.3048 0.9906)
			(stroke
				(width 0.1)
				(type default)
			)
			(layer "B.Fab")
		)
		(pad "1" smd rect
			(at 0 0 90)
			(size 0.508 0.508)
			(layers "B.Cu" "B.Mask" "B.Paste")
			(net "P3V3_STBY")
		)
		(pad "2" smd rect
			(at 0 0.889 90)
			(size 0.508 0.508)
			(layers "B.Cu" "B.Mask" "B.Paste")
			(net "GND")
		)
		(zone
			(layer "B.Cu")
			(hatch none 0.5)
			(connect_pads
				(clearance 0)
			)
			(min_thickness 0.25)
			(keepout
				(tracks not_allowed)
				(vias allowed)
				(pads allowed)
				(copperpour not_allowed)
				(footprints allowed)
			)
			(placement
				(enabled no)
				(sheetname "")
			)
			(fill
				(thermal_gap 0.5)
				(thermal_bridge_width 0.5)
				(island_removal_mode 0)
			)
			(polygon
				(pts
					(xy 410.844492 -30.853888) (xy 410.844492 -31.361888) (xy 411.225492 -31.361888) (xy 411.225492 -30.853888)
				)
			)
		)
		(zone
			(layer "B.Cu")
			(hatch none 0.5)
			(connect_pads
				(clearance 0)
			)
			(min_thickness 0.25)
			(keepout
				(tracks allowed)
				(vias not_allowed)
				(pads allowed)
				(copperpour not_allowed)
				(footprints allowed)
			)
			(placement
				(enabled no)
				(sheetname "")
			)
			(fill
				(thermal_gap 0.5)
				(thermal_bridge_width 0.5)
				(island_removal_mode 0)
			)
			(polygon
				(pts
					(xy 411.225492 -30.853888) (xy 411.225492 -31.361888) (xy 410.844492 -31.361888) (xy 410.844492 -30.853888)
				)
			)
		)
	)
	(footprint ""
		(layer "B.Cu")
		(at 205.74 -106.299 -90)
		(property "Reference" "R6N10"
			(at 0 0 90)
			(layer "B.SilkS")
			(hide yes)
			(effects
				(font
					(size 1.27 1.27)
				)
				(justify mirror)
			)
		)
		(property "Value" ""
			(at 0 0 90)
			(layer "B.Fab")
			(effects
				(font
					(size 1.27 1.27)
				)
				(justify mirror)
			)
		)
		(duplicate_pad_numbers_are_jumpers no)
		(fp_poly
			(pts
				(xy 0.2794 -0.1016) (xy -0.2794 -0.1016) (xy -0.2794 0.9906) (xy 0.2794 0.9906)
			)
			(stroke
				(width 0)
				(type default)
			)
			(fill no)
			(layer "B.CrtYd")
		)
		(fp_line
			(start -0.2794 0.9906)
			(end -0.2794 -0.1016)
			(stroke
				(width 0.1)
				(type default)
			)
			(layer "B.Fab")
		)
		(fp_line
			(start 0.2794 0.9906)
			(end -0.2794 0.9906)
			(stroke
				(width 0.1)
				(type default)
			)
			(layer "B.Fab")
		)
		(fp_line
			(start -0.2794 -0.1016)
			(end 0.2794 -0.1016)
			(stroke
				(width 0.1)
				(type default)
			)
			(layer "B.Fab")
		)
		(fp_line
			(start 0.2794 -0.1016)
			(end 0.2794 0.9906)
			(stroke
				(width 0.1)
				(type default)
			)
			(layer "B.Fab")
		)
		(pad "1" smd rect
			(at 0 0 90)
			(size 0.508 0.508)
			(layers "B.Cu" "B.Mask" "B.Paste")
			(net "SVID_ALERT0_CPU0_N")
		)
		(pad "2" smd rect
			(at 0 0.889 90)
			(size 0.508 0.508)
			(layers "B.Cu" "B.Mask" "B.Paste")
			(net "SVID_ALERT0_CPU0_R_N")
		)
		(zone
			(layer "B.Cu")
			(hatch none 0.5)
			(connect_pads
				(clearance 0)
			)
			(min_thickness 0.25)
			(keepout
				(tracks not_allowed)
				(vias allowed)
				(pads allowed)
				(copperpour not_allowed)
				(footprints allowed)
			)
			(placement
				(enabled no)
				(sheetname "")
			)
			(fill
				(thermal_gap 0.5)
				(thermal_bridge_width 0.5)
				(island_removal_mode 0)
			)
			(polygon
				(pts
					(xy 205.105 -106.045) (xy 205.105 -106.553) (xy 205.486 -106.553) (xy 205.486 -106.045)
				)
			)
		)
		(zone
			(layer "B.Cu")
			(hatch none 0.5)
			(connect_pads
				(clearance 0)
			)
			(min_thickness 0.25)
			(keepout
				(tracks allowed)
				(vias not_allowed)
				(pads allowed)
				(copperpour not_allowed)
				(footprints allowed)
			)
			(placement
				(enabled no)
				(sheetname "")
			)
			(fill
				(thermal_gap 0.5)
				(thermal_bridge_width 0.5)
				(island_removal_mode 0)
			)
			(polygon
				(pts
					(xy 205.486 -106.045) (xy 205.486 -106.553) (xy 205.105 -106.553) (xy 205.105 -106.045)
				)
			)
		)
	)
	(footprint ""
		(layer "B.Cu")
		(at 19.431 -82.423 -90)
		(property "Reference" "R9P11"
			(at 0 0 90)
			(layer "B.SilkS")
			(hide yes)
			(effects
				(font
					(size 1.27 1.27)
				)
				(justify mirror)
			)
		)
		(property "Value" ""
			(at 0 0 90)
			(layer "B.Fab")
			(effects
				(font
					(size 1.27 1.27)
				)
				(justify mirror)
			)
		)
		(duplicate_pad_numbers_are_jumpers no)
		(fp_poly
			(pts
				(xy 0.2794 -0.1016) (xy -0.2794 -0.1016) (xy -0.2794 0.9906) (xy 0.2794 0.9906)
			)
			(stroke
				(width 0)
				(type default)
			)
			(fill no)
			(layer "B.CrtYd")
		)
		(fp_line
			(start -0.2794 0.9906)
			(end -0.2794 -0.1016)
			(stroke
				(width 0.1)
				(type default)
			)
			(layer "B.Fab")
		)
		(fp_line
			(start 0.2794 0.9906)
			(end -0.2794 0.9906)
			(stroke
				(width 0.1)
				(type default)
			)
			(layer "B.Fab")
		)
		(fp_line
			(start -0.2794 -0.1016)
			(end 0.2794 -0.1016)
			(stroke
				(width 0.1)
				(type default)
			)
			(layer "B.Fab")
		)
		(fp_line
			(start 0.2794 -0.1016)
			(end 0.2794 0.9906)
			(stroke
				(width 0.1)
				(type default)
			)
			(layer "B.Fab")
		)
		(pad "1" smd rect
			(at 0 0 90)
			(size 0.508 0.508)
			(layers "B.Cu" "B.Mask" "B.Paste")
			(net "A_P12V_STBY_FP_TRIGGER")
		)
		(pad "2" smd rect
			(at 0 0.889 90)
			(size 0.508 0.508)
			(layers "B.Cu" "B.Mask" "B.Paste")
			(net "AGND_HSC")
		)
		(zone
			(layer "B.Cu")
			(hatch none 0.5)
			(connect_pads
				(clearance 0)
			)
			(min_thickness 0.25)
			(keepout
				(tracks not_allowed)
				(vias allowed)
				(pads allowed)
				(copperpour not_allowed)
				(footprints allowed)
			)
			(placement
				(enabled no)
				(sheetname "")
			)
			(fill
				(thermal_gap 0.5)
				(thermal_bridge_width 0.5)
				(island_removal_mode 0)
			)
			(polygon
				(pts
					(xy 18.796 -82.169) (xy 18.796 -82.677) (xy 19.177 -82.677) (xy 19.177 -82.169)
				)
			)
		)
		(zone
			(layer "B.Cu")
			(hatch none 0.5)
			(connect_pads
				(clearance 0)
			)
			(min_thickness 0.25)
			(keepout
				(tracks allowed)
				(vias not_allowed)
				(pads allowed)
				(copperpour not_allowed)
				(footprints allowed)
			)
			(placement
				(enabled no)
				(sheetname "")
			)
			(fill
				(thermal_gap 0.5)
				(thermal_bridge_width 0.5)
				(island_removal_mode 0)
			)
			(polygon
				(pts
					(xy 19.177 -82.169) (xy 19.177 -82.677) (xy 18.796 -82.677) (xy 18.796 -82.169)
				)
			)
		)
	)
)
